FILE_TYPE = MACRO_DRAWING;
SET COLOR_WIRE YELLOW;
SET COLOR_PROP ORANGE;
SET COLOR_DOT WHITE;
SET COLOR_ARC YELLOW;
SET COLOR_BODY GREEN;
SET COLOR_NOTE PURPLE;
SET PROP_DISPLAY VALUE;
SET PAGE_NUMBER P395;
FORCEADD PT5161LRS..6
(-7450 4425);
FORCEPROP 1 LAST LOCATION U6015
J 0
(-7800 6050);
DISPLAY 0.723404 (-7800 6050);
PAINT GREEN (-7800 6050);
FORCEPROP 0 LAST $SEC 6
J 0
(-7800 6200);
DISPLAY 0.680851 (-7800 6200);
PAINT MONO (-7800 6200);
DISPLAY INVISIBLE (-7800 6200);
FORCEPROP 0 LAST CDS_SEC 6
J 0
(-7800 6200);
DISPLAY 0.680851 (-7800 6200);
DISPLAY INVISIBLE (-7800 6200);
FORCEPROP 0 LASTPIN (-7000 5575) $PN P29
J 0
(-6990 5585);
DISPLAY 0.680851 (-6990 5585);
PAINT MONO (-6990 5585);
FORCEPROP 0 LASTPIN (-7000 5225) $PN AA29
J 0
(-6990 5235);
DISPLAY 0.680851 (-6990 5235);
PAINT MONO (-6990 5235);
FORCEPROP 0 LASTPIN (-7000 4875) $PN AH29
J 0
(-6990 4885);
DISPLAY 0.680851 (-6990 4885);
PAINT MONO (-6990 4885);
FORCEPROP 0 LASTPIN (-7000 4525) $PN AR29
J 0
(-6990 4535);
DISPLAY 0.680851 (-6990 4535);
PAINT MONO (-6990 4535);
FORCEPROP 0 LASTPIN (-7000 4175) $PN BB29
J 0
(-6990 4185);
DISPLAY 0.680851 (-6990 4185);
PAINT MONO (-6990 4185);
FORCEPROP 0 LASTPIN (-7000 3825) $PN BJ29
J 0
(-6990 3835);
DISPLAY 0.680851 (-6990 3835);
PAINT MONO (-6990 3835);
FORCEPROP 0 LASTPIN (-7000 3475) $PN BT29
J 0
(-6990 3485);
DISPLAY 0.680851 (-6990 3485);
PAINT MONO (-6990 3485);
FORCEPROP 0 LASTPIN (-7000 3125) $PN CC29
J 0
(-6990 3135);
DISPLAY 0.680851 (-6990 3135);
PAINT MONO (-6990 3135);
FORCEPROP 0 LASTPIN (-7000 5675) $PN M26
J 0
(-6990 5685);
DISPLAY 0.680851 (-6990 5685);
PAINT MONO (-6990 5685);
FORCEPROP 0 LASTPIN (-7000 5325) $PN W26
J 0
(-6990 5335);
DISPLAY 0.680851 (-6990 5335);
PAINT MONO (-6990 5335);
FORCEPROP 0 LASTPIN (-7000 4975) $PN AF26
J 0
(-6990 4985);
DISPLAY 0.680851 (-6990 4985);
PAINT MONO (-6990 4985);
FORCEPROP 0 LASTPIN (-7000 4625) $PN AN26
J 0
(-6990 4635);
DISPLAY 0.680851 (-6990 4635);
PAINT MONO (-6990 4635);
FORCEPROP 0 LASTPIN (-7000 4275) $PN AY26
J 0
(-6990 4285);
DISPLAY 0.680851 (-6990 4285);
PAINT MONO (-6990 4285);
FORCEPROP 0 LASTPIN (-7000 3925) $PN BG26
J 0
(-6990 3935);
DISPLAY 0.680851 (-6990 3935);
PAINT MONO (-6990 3935);
FORCEPROP 0 LASTPIN (-7000 3575) $PN BP26
J 0
(-6990 3585);
DISPLAY 0.680851 (-6990 3585);
PAINT MONO (-6990 3585);
FORCEPROP 0 LASTPIN (-7000 3225) $PN CA26
J 0
(-6990 3235);
DISPLAY 0.680851 (-6990 3235);
PAINT MONO (-6990 3235);
FORCEPROP 2 LAST VALUE PT5161LRS
J 0
(-7800 6100);
DISPLAY 0.680851 (-7800 6100);
FORCEPROP 1 LAST MATERIAL IC
J 0
(-7800 5900);
DISPLAY 0.723404 (-7800 5900);
PAINT GREEN (-7800 5900);
FORCEPROP 2 LAST PART_TYPE SMLF
J 0
(-7800 6150);
DISPLAY 0.680851 (-7800 6150);
FORCEPROP 2 LAST CDS_LIB pure_quanta
J 0
(-7450 4425);
DISPLAY INVISIBLE (-7450 4425);
FORCEPROP 1 LAST CDS_LMAN_SYM_OUTLINE -350,1450,300,-1400
J 0
(-7450 4425);
DISPLAY 0.468085 (-7450 4425);
PAINT GREEN (-7450 4425);
DISPLAY INVISIBLE (-7450 4425);
FORCEPROP 1 LAST NEEDS_NO_SIZE TRUE
J 0
(-7450 4425);
DISPLAY 0.723404 (-7450 4425);
PAINT GREEN (-7450 4425);
DISPLAY INVISIBLE (-7450 4425);
FORCEPROP 1 LAST PATH I1
J 0
(-7450 4425);
DISPLAY 0.723404 (-7450 4425);
PAINT GREEN (-7450 4425);
DISPLAY INVISIBLE (-7450 4425);
FORCEPROP 1 LAST PART_NUMBER AJ051610U03
J 0
(-7800 5975);
DISPLAY 0.723404 (-7800 5975);
PAINT GREEN (-7800 5975);
DISPLAY INVISIBLE (-7800 5975);
FORCEADD TAP..1
(-6425 5325);
FORCEPROP 3 LASTPIN (-6475 5325) SIG_NAME P5E_CPU1_P1_RX_DP<14>
J 0
(-6465 5335);
DISPLAY 0.659574 (-6465 5335);
PAINT MONO (-6465 5335);
DISPLAY INVISIBLE (-6465 5335);
FORCEPROP 1 LASTPIN (-6475 5325) BN 14
J 0
(-6487 5333);
DISPLAY 0.680851 (-6487 5333);
PAINT GREEN (-6487 5333);
FORCEPROP 2 LAST CDS_LIB standard
J 0
(-6425 5325);
DISPLAY INVISIBLE (-6425 5325);
FORCEPROP 1 LAST BODY_TYPE PLUMBING
J 0
(-6425 5375);
DISPLAY 0.872340 (-6425 5375);
PAINT GREEN (-6425 5375);
DISPLAY INVISIBLE (-6425 5375);
FORCEPROP 1 LAST HDL_TAP TRUE
J 0
(-6100 5200);
DISPLAY 0.872340 (-6100 5200);
DISPLAY INVISIBLE (-6100 5200);
FORCEPROP 1 LAST PATH I10
J 0
(-6427 5325);
DISPLAY 0.872340 (-6427 5325);
PAINT GREEN (-6427 5325);
DISPLAY INVISIBLE (-6427 5325);
FORCEADD TAP..1
(-6425 4975);
FORCEPROP 3 LASTPIN (-6475 4975) SIG_NAME P5E_CPU1_P1_RX_DP<13>
J 0
(-6465 4985);
DISPLAY 0.659574 (-6465 4985);
PAINT MONO (-6465 4985);
DISPLAY INVISIBLE (-6465 4985);
FORCEPROP 1 LASTPIN (-6475 4975) BN 13
J 0
(-6487 4983);
DISPLAY 0.680851 (-6487 4983);
PAINT GREEN (-6487 4983);
FORCEPROP 2 LAST CDS_LIB standard
J 0
(-6425 4975);
DISPLAY INVISIBLE (-6425 4975);
FORCEPROP 1 LAST BODY_TYPE PLUMBING
J 0
(-6425 5025);
DISPLAY 0.872340 (-6425 5025);
PAINT GREEN (-6425 5025);
DISPLAY INVISIBLE (-6425 5025);
FORCEPROP 1 LAST HDL_TAP TRUE
J 0
(-6100 4850);
DISPLAY 0.872340 (-6100 4850);
DISPLAY INVISIBLE (-6100 4850);
FORCEPROP 1 LAST PATH I11
J 0
(-6427 4975);
DISPLAY 0.872340 (-6427 4975);
PAINT GREEN (-6427 4975);
DISPLAY INVISIBLE (-6427 4975);
FORCEADD TAP..1
(-6425 4625);
FORCEPROP 3 LASTPIN (-6475 4625) SIG_NAME P5E_CPU1_P1_RX_DP<12>
J 0
(-6465 4635);
DISPLAY 0.659574 (-6465 4635);
PAINT MONO (-6465 4635);
DISPLAY INVISIBLE (-6465 4635);
FORCEPROP 1 LASTPIN (-6475 4625) BN 12
J 0
(-6487 4633);
DISPLAY 0.680851 (-6487 4633);
PAINT GREEN (-6487 4633);
FORCEPROP 2 LAST CDS_LIB standard
J 0
(-6425 4625);
DISPLAY INVISIBLE (-6425 4625);
FORCEPROP 1 LAST BODY_TYPE PLUMBING
J 0
(-6425 4675);
DISPLAY 0.872340 (-6425 4675);
PAINT GREEN (-6425 4675);
DISPLAY INVISIBLE (-6425 4675);
FORCEPROP 1 LAST HDL_TAP TRUE
J 0
(-6100 4500);
DISPLAY 0.872340 (-6100 4500);
DISPLAY INVISIBLE (-6100 4500);
FORCEPROP 1 LAST PATH I12
J 0
(-6427 4625);
DISPLAY 0.872340 (-6427 4625);
PAINT GREEN (-6427 4625);
DISPLAY INVISIBLE (-6427 4625);
FORCEADD TAP..1
(-6225 4525);
FORCEPROP 3 LASTPIN (-6275 4525) SIG_NAME P5E_CPU1_P1_RX_DN<12>
J 0
(-6265 4535);
DISPLAY 0.659574 (-6265 4535);
PAINT MONO (-6265 4535);
DISPLAY INVISIBLE (-6265 4535);
FORCEPROP 1 LASTPIN (-6275 4525) BN 12
J 0
(-6287 4533);
DISPLAY 0.680851 (-6287 4533);
PAINT GREEN (-6287 4533);
FORCEPROP 2 LAST CDS_LIB standard
J 0
(-6225 4525);
DISPLAY INVISIBLE (-6225 4525);
FORCEPROP 1 LAST BODY_TYPE PLUMBING
J 0
(-6225 4575);
DISPLAY 0.872340 (-6225 4575);
PAINT GREEN (-6225 4575);
DISPLAY INVISIBLE (-6225 4575);
FORCEPROP 1 LAST HDL_TAP TRUE
J 0
(-5900 4400);
DISPLAY 0.872340 (-5900 4400);
DISPLAY INVISIBLE (-5900 4400);
FORCEPROP 1 LAST PATH I13
J 0
(-6227 4525);
DISPLAY 0.872340 (-6227 4525);
PAINT GREEN (-6227 4525);
DISPLAY INVISIBLE (-6227 4525);
FORCEADD TAP..1
(-6225 4875);
FORCEPROP 3 LASTPIN (-6275 4875) SIG_NAME P5E_CPU1_P1_RX_DN<13>
J 0
(-6265 4885);
DISPLAY 0.659574 (-6265 4885);
PAINT MONO (-6265 4885);
DISPLAY INVISIBLE (-6265 4885);
FORCEPROP 1 LASTPIN (-6275 4875) BN 13
J 0
(-6287 4883);
DISPLAY 0.680851 (-6287 4883);
PAINT GREEN (-6287 4883);
FORCEPROP 2 LAST CDS_LIB standard
J 0
(-6225 4875);
DISPLAY INVISIBLE (-6225 4875);
FORCEPROP 1 LAST BODY_TYPE PLUMBING
J 0
(-6225 4925);
DISPLAY 0.872340 (-6225 4925);
PAINT GREEN (-6225 4925);
DISPLAY INVISIBLE (-6225 4925);
FORCEPROP 1 LAST HDL_TAP TRUE
J 0
(-5900 4750);
DISPLAY 0.872340 (-5900 4750);
DISPLAY INVISIBLE (-5900 4750);
FORCEPROP 1 LAST PATH I14
J 0
(-6227 4875);
DISPLAY 0.872340 (-6227 4875);
PAINT GREEN (-6227 4875);
DISPLAY INVISIBLE (-6227 4875);
FORCEADD TAP..1
(-6225 5225);
FORCEPROP 3 LASTPIN (-6275 5225) SIG_NAME P5E_CPU1_P1_RX_DN<14>
J 0
(-6265 5235);
DISPLAY 0.659574 (-6265 5235);
PAINT MONO (-6265 5235);
DISPLAY INVISIBLE (-6265 5235);
FORCEPROP 1 LASTPIN (-6275 5225) BN 14
J 0
(-6287 5233);
DISPLAY 0.680851 (-6287 5233);
PAINT GREEN (-6287 5233);
FORCEPROP 2 LAST CDS_LIB standard
J 0
(-6225 5225);
DISPLAY INVISIBLE (-6225 5225);
FORCEPROP 1 LAST BODY_TYPE PLUMBING
J 0
(-6225 5275);
DISPLAY 0.872340 (-6225 5275);
PAINT GREEN (-6225 5275);
DISPLAY INVISIBLE (-6225 5275);
FORCEPROP 1 LAST HDL_TAP TRUE
J 0
(-5900 5100);
DISPLAY 0.872340 (-5900 5100);
DISPLAY INVISIBLE (-5900 5100);
FORCEPROP 1 LAST PATH I15
J 0
(-6227 5225);
DISPLAY 0.872340 (-6227 5225);
PAINT GREEN (-6227 5225);
DISPLAY INVISIBLE (-6227 5225);
FORCEADD TAP..1
(-6425 5675);
FORCEPROP 3 LASTPIN (-6475 5675) SIG_NAME P5E_CPU1_P1_RX_DP<15>
J 0
(-6465 5685);
DISPLAY 0.659574 (-6465 5685);
PAINT MONO (-6465 5685);
DISPLAY INVISIBLE (-6465 5685);
FORCEPROP 1 LASTPIN (-6475 5675) BN 15
J 0
(-6487 5683);
DISPLAY 0.680851 (-6487 5683);
PAINT GREEN (-6487 5683);
FORCEPROP 2 LAST CDS_LIB standard
J 0
(-6425 5675);
DISPLAY INVISIBLE (-6425 5675);
FORCEPROP 1 LAST BODY_TYPE PLUMBING
J 0
(-6425 5725);
DISPLAY 0.872340 (-6425 5725);
PAINT GREEN (-6425 5725);
DISPLAY INVISIBLE (-6425 5725);
FORCEPROP 1 LAST HDL_TAP TRUE
J 0
(-6100 5550);
DISPLAY 0.872340 (-6100 5550);
DISPLAY INVISIBLE (-6100 5550);
FORCEPROP 1 LAST PATH I16
J 0
(-6427 5675);
DISPLAY 0.872340 (-6427 5675);
PAINT GREEN (-6427 5675);
DISPLAY INVISIBLE (-6427 5675);
FORCEADD TAP..1
(-6225 5575);
FORCEPROP 3 LASTPIN (-6275 5575) SIG_NAME P5E_CPU1_P1_RX_DN<15>
J 0
(-6265 5585);
DISPLAY 0.659574 (-6265 5585);
PAINT MONO (-6265 5585);
DISPLAY INVISIBLE (-6265 5585);
FORCEPROP 1 LASTPIN (-6275 5575) BN 15
J 0
(-6287 5583);
DISPLAY 0.680851 (-6287 5583);
PAINT GREEN (-6287 5583);
FORCEPROP 2 LAST CDS_LIB standard
J 0
(-6225 5575);
DISPLAY INVISIBLE (-6225 5575);
FORCEPROP 1 LAST BODY_TYPE PLUMBING
J 0
(-6225 5625);
DISPLAY 0.872340 (-6225 5625);
PAINT GREEN (-6225 5625);
DISPLAY INVISIBLE (-6225 5625);
FORCEPROP 1 LAST HDL_TAP TRUE
J 0
(-5900 5450);
DISPLAY 0.872340 (-5900 5450);
DISPLAY INVISIBLE (-5900 5450);
FORCEPROP 1 LAST PATH I17
J 0
(-6227 5575);
DISPLAY 0.872340 (-6227 5575);
PAINT GREEN (-6227 5575);
DISPLAY INVISIBLE (-6227 5575);
FORCEADD OFFPAGE..5
R 2
(-5225 5650);
FORCEPROP 2 LAST $XR0 51 
J 0
(-5036 5650);
DISPLAY 0.638298 (-5036 5650);
PAINT MONO (-5036 5650);
FORCEPROP 2 LAST CDS_LIB standard
J 0
(-5225 5650);
DISPLAY INVISIBLE (-5225 5650);
FORCEPROP 1 LAST OFFPAGE TRUE
J 2
(-5550 5525);
DISPLAY 0.872340 (-5550 5525);
PAINT GREEN (-5550 5525);
DISPLAY INVISIBLE (-5550 5525);
FORCEPROP 1 LAST COMMENT_BODY TRUE
J 2
(-5325 5575);
DISPLAY 0.872340 (-5325 5575);
PAINT GREEN (-5325 5575);
DISPLAY INVISIBLE (-5325 5575);
FORCEPROP 2 LAST PATH I18
J 0
(-5050 5725);
DISPLAY 0.680851 (-5050 5725);
DISPLAY INVISIBLE (-5050 5725);
FORCEADD OFFPAGE..5
R 2
(-5200 5775);
FORCEPROP 2 LAST $XR0 51 
J 0
(-5011 5775);
DISPLAY 0.638298 (-5011 5775);
PAINT MONO (-5011 5775);
FORCEPROP 2 LAST CDS_LIB standard
J 0
(-5200 5775);
DISPLAY INVISIBLE (-5200 5775);
FORCEPROP 1 LAST OFFPAGE TRUE
J 2
(-5525 5650);
DISPLAY 0.872340 (-5525 5650);
PAINT GREEN (-5525 5650);
DISPLAY INVISIBLE (-5525 5650);
FORCEPROP 1 LAST COMMENT_BODY TRUE
J 2
(-5300 5700);
DISPLAY 0.872340 (-5300 5700);
PAINT GREEN (-5300 5700);
DISPLAY INVISIBLE (-5300 5700);
FORCEPROP 2 LAST PATH I19
J 0
(-5025 5850);
DISPLAY 0.680851 (-5025 5850);
DISPLAY INVISIBLE (-5025 5850);
FORCEADD TAP..1
(-6425 3225);
FORCEPROP 3 LASTPIN (-6475 3225) SIG_NAME P5E_CPU1_P1_RX_DP<8>
J 0
(-6465 3235);
DISPLAY 0.659574 (-6465 3235);
PAINT MONO (-6465 3235);
DISPLAY INVISIBLE (-6465 3235);
FORCEPROP 1 LASTPIN (-6475 3225) BN 8
J 0
(-6487 3233);
DISPLAY 0.680851 (-6487 3233);
PAINT GREEN (-6487 3233);
FORCEPROP 2 LAST CDS_LIB standard
J 0
(-6425 3225);
DISPLAY INVISIBLE (-6425 3225);
FORCEPROP 1 LAST BODY_TYPE PLUMBING
J 0
(-6425 3275);
DISPLAY 0.872340 (-6425 3275);
PAINT GREEN (-6425 3275);
DISPLAY INVISIBLE (-6425 3275);
FORCEPROP 1 LAST HDL_TAP TRUE
J 0
(-6100 3100);
DISPLAY 0.872340 (-6100 3100);
DISPLAY INVISIBLE (-6100 3100);
FORCEPROP 1 LAST PATH I2
J 0
(-6427 3225);
DISPLAY 0.872340 (-6427 3225);
PAINT GREEN (-6427 3225);
DISPLAY INVISIBLE (-6427 3225);
FORCEADD TAP..1
(-1900 3300);
FORCEPROP 3 LASTPIN (-1950 3300) SIG_NAME P5E_CPU1_P1_RX_DP<0>
J 0
(-1940 3310);
DISPLAY 0.659574 (-1940 3310);
PAINT MONO (-1940 3310);
DISPLAY INVISIBLE (-1940 3310);
FORCEPROP 1 LASTPIN (-1950 3300) BN 0
J 0
(-1962 3308);
DISPLAY 0.680851 (-1962 3308);
PAINT GREEN (-1962 3308);
FORCEPROP 2 LAST CDS_LIB standard
J 0
(-1900 3300);
DISPLAY INVISIBLE (-1900 3300);
FORCEPROP 1 LAST BODY_TYPE PLUMBING
J 0
(-1900 3350);
DISPLAY 0.872340 (-1900 3350);
PAINT GREEN (-1900 3350);
DISPLAY INVISIBLE (-1900 3350);
FORCEPROP 1 LAST HDL_TAP TRUE
J 0
(-1575 3175);
DISPLAY 0.872340 (-1575 3175);
DISPLAY INVISIBLE (-1575 3175);
FORCEPROP 1 LAST PATH I20
J 0
(-1902 3300);
DISPLAY 0.872340 (-1902 3300);
PAINT GREEN (-1902 3300);
DISPLAY INVISIBLE (-1902 3300);
FORCEADD TAP..1
(-1900 3650);
FORCEPROP 3 LASTPIN (-1950 3650) SIG_NAME P5E_CPU1_P1_RX_DP<1>
J 0
(-1940 3660);
DISPLAY 0.659574 (-1940 3660);
PAINT MONO (-1940 3660);
DISPLAY INVISIBLE (-1940 3660);
FORCEPROP 1 LASTPIN (-1950 3650) BN 1
J 0
(-1962 3658);
DISPLAY 0.680851 (-1962 3658);
PAINT GREEN (-1962 3658);
FORCEPROP 2 LAST CDS_LIB standard
J 0
(-1900 3650);
DISPLAY INVISIBLE (-1900 3650);
FORCEPROP 1 LAST BODY_TYPE PLUMBING
J 0
(-1900 3700);
DISPLAY 0.872340 (-1900 3700);
PAINT GREEN (-1900 3700);
DISPLAY INVISIBLE (-1900 3700);
FORCEPROP 1 LAST HDL_TAP TRUE
J 0
(-1575 3525);
DISPLAY 0.872340 (-1575 3525);
DISPLAY INVISIBLE (-1575 3525);
FORCEPROP 1 LAST PATH I21
J 0
(-1902 3650);
DISPLAY 0.872340 (-1902 3650);
PAINT GREEN (-1902 3650);
DISPLAY INVISIBLE (-1902 3650);
FORCEADD TAP..1
(-1900 4000);
FORCEPROP 3 LASTPIN (-1950 4000) SIG_NAME P5E_CPU1_P1_RX_DP<2>
J 0
(-1940 4010);
DISPLAY 0.659574 (-1940 4010);
PAINT MONO (-1940 4010);
DISPLAY INVISIBLE (-1940 4010);
FORCEPROP 1 LASTPIN (-1950 4000) BN 2
J 0
(-1962 4008);
DISPLAY 0.680851 (-1962 4008);
PAINT GREEN (-1962 4008);
FORCEPROP 2 LAST CDS_LIB standard
J 0
(-1900 4000);
DISPLAY INVISIBLE (-1900 4000);
FORCEPROP 1 LAST BODY_TYPE PLUMBING
J 0
(-1900 4050);
DISPLAY 0.872340 (-1900 4050);
PAINT GREEN (-1900 4050);
DISPLAY INVISIBLE (-1900 4050);
FORCEPROP 1 LAST HDL_TAP TRUE
J 0
(-1575 3875);
DISPLAY 0.872340 (-1575 3875);
DISPLAY INVISIBLE (-1575 3875);
FORCEPROP 1 LAST PATH I22
J 0
(-1902 4000);
DISPLAY 0.872340 (-1902 4000);
PAINT GREEN (-1902 4000);
DISPLAY INVISIBLE (-1902 4000);
FORCEADD TAP..1
(-1900 4350);
FORCEPROP 3 LASTPIN (-1950 4350) SIG_NAME P5E_CPU1_P1_RX_DP<3>
J 0
(-1940 4360);
DISPLAY 0.659574 (-1940 4360);
PAINT MONO (-1940 4360);
DISPLAY INVISIBLE (-1940 4360);
FORCEPROP 1 LASTPIN (-1950 4350) BN 3
J 0
(-1962 4358);
DISPLAY 0.680851 (-1962 4358);
PAINT GREEN (-1962 4358);
FORCEPROP 2 LAST CDS_LIB standard
J 0
(-1900 4350);
DISPLAY INVISIBLE (-1900 4350);
FORCEPROP 1 LAST BODY_TYPE PLUMBING
J 0
(-1900 4400);
DISPLAY 0.872340 (-1900 4400);
PAINT GREEN (-1900 4400);
DISPLAY INVISIBLE (-1900 4400);
FORCEPROP 1 LAST HDL_TAP TRUE
J 0
(-1575 4225);
DISPLAY 0.872340 (-1575 4225);
DISPLAY INVISIBLE (-1575 4225);
FORCEPROP 1 LAST PATH I23
J 0
(-1902 4350);
DISPLAY 0.872340 (-1902 4350);
PAINT GREEN (-1902 4350);
DISPLAY INVISIBLE (-1902 4350);
FORCEADD TAP..1
(-1700 3200);
FORCEPROP 3 LASTPIN (-1750 3200) SIG_NAME P5E_CPU1_P1_RX_DN<0>
J 0
(-1740 3210);
DISPLAY 0.659574 (-1740 3210);
PAINT MONO (-1740 3210);
DISPLAY INVISIBLE (-1740 3210);
FORCEPROP 1 LASTPIN (-1750 3200) BN 0
J 0
(-1762 3208);
DISPLAY 0.680851 (-1762 3208);
PAINT GREEN (-1762 3208);
FORCEPROP 2 LAST CDS_LIB standard
J 0
(-1700 3200);
DISPLAY INVISIBLE (-1700 3200);
FORCEPROP 1 LAST BODY_TYPE PLUMBING
J 0
(-1700 3250);
DISPLAY 0.872340 (-1700 3250);
PAINT GREEN (-1700 3250);
DISPLAY INVISIBLE (-1700 3250);
FORCEPROP 1 LAST HDL_TAP TRUE
J 0
(-1375 3075);
DISPLAY 0.872340 (-1375 3075);
DISPLAY INVISIBLE (-1375 3075);
FORCEPROP 1 LAST PATH I24
J 0
(-1702 3200);
DISPLAY 0.872340 (-1702 3200);
PAINT GREEN (-1702 3200);
DISPLAY INVISIBLE (-1702 3200);
FORCEADD TAP..1
(-1700 3550);
FORCEPROP 3 LASTPIN (-1750 3550) SIG_NAME P5E_CPU1_P1_RX_DN<1>
J 0
(-1740 3560);
DISPLAY 0.659574 (-1740 3560);
PAINT MONO (-1740 3560);
DISPLAY INVISIBLE (-1740 3560);
FORCEPROP 1 LASTPIN (-1750 3550) BN 1
J 0
(-1762 3558);
DISPLAY 0.680851 (-1762 3558);
PAINT GREEN (-1762 3558);
FORCEPROP 2 LAST CDS_LIB standard
J 0
(-1700 3550);
DISPLAY INVISIBLE (-1700 3550);
FORCEPROP 1 LAST BODY_TYPE PLUMBING
J 0
(-1700 3600);
DISPLAY 0.872340 (-1700 3600);
PAINT GREEN (-1700 3600);
DISPLAY INVISIBLE (-1700 3600);
FORCEPROP 1 LAST HDL_TAP TRUE
J 0
(-1375 3425);
DISPLAY 0.872340 (-1375 3425);
DISPLAY INVISIBLE (-1375 3425);
FORCEPROP 1 LAST PATH I25
J 0
(-1702 3550);
DISPLAY 0.872340 (-1702 3550);
PAINT GREEN (-1702 3550);
DISPLAY INVISIBLE (-1702 3550);
FORCEADD TAP..1
(-1700 3900);
FORCEPROP 3 LASTPIN (-1750 3900) SIG_NAME P5E_CPU1_P1_RX_DN<2>
J 0
(-1740 3910);
DISPLAY 0.659574 (-1740 3910);
PAINT MONO (-1740 3910);
DISPLAY INVISIBLE (-1740 3910);
FORCEPROP 1 LASTPIN (-1750 3900) BN 2
J 0
(-1762 3908);
DISPLAY 0.680851 (-1762 3908);
PAINT GREEN (-1762 3908);
FORCEPROP 2 LAST CDS_LIB standard
J 0
(-1700 3900);
DISPLAY INVISIBLE (-1700 3900);
FORCEPROP 1 LAST BODY_TYPE PLUMBING
J 0
(-1700 3950);
DISPLAY 0.872340 (-1700 3950);
PAINT GREEN (-1700 3950);
DISPLAY INVISIBLE (-1700 3950);
FORCEPROP 1 LAST HDL_TAP TRUE
J 0
(-1375 3775);
DISPLAY 0.872340 (-1375 3775);
DISPLAY INVISIBLE (-1375 3775);
FORCEPROP 1 LAST PATH I26
J 0
(-1702 3900);
DISPLAY 0.872340 (-1702 3900);
PAINT GREEN (-1702 3900);
DISPLAY INVISIBLE (-1702 3900);
FORCEADD TAP..1
(-1700 4250);
FORCEPROP 3 LASTPIN (-1750 4250) SIG_NAME P5E_CPU1_P1_RX_DN<3>
J 0
(-1740 4260);
DISPLAY 0.659574 (-1740 4260);
PAINT MONO (-1740 4260);
DISPLAY INVISIBLE (-1740 4260);
FORCEPROP 1 LASTPIN (-1750 4250) BN 3
J 0
(-1762 4258);
DISPLAY 0.680851 (-1762 4258);
PAINT GREEN (-1762 4258);
FORCEPROP 2 LAST CDS_LIB standard
J 0
(-1700 4250);
DISPLAY INVISIBLE (-1700 4250);
FORCEPROP 1 LAST BODY_TYPE PLUMBING
J 0
(-1700 4300);
DISPLAY 0.872340 (-1700 4300);
PAINT GREEN (-1700 4300);
DISPLAY INVISIBLE (-1700 4300);
FORCEPROP 1 LAST HDL_TAP TRUE
J 0
(-1375 4125);
DISPLAY 0.872340 (-1375 4125);
DISPLAY INVISIBLE (-1375 4125);
FORCEPROP 1 LAST PATH I27
J 0
(-1702 4250);
DISPLAY 0.872340 (-1702 4250);
PAINT GREEN (-1702 4250);
DISPLAY INVISIBLE (-1702 4250);
FORCEADD TAP..1
(-1900 4700);
FORCEPROP 3 LASTPIN (-1950 4700) SIG_NAME P5E_CPU1_P1_RX_DP<4>
J 0
(-1940 4710);
DISPLAY 0.659574 (-1940 4710);
PAINT MONO (-1940 4710);
DISPLAY INVISIBLE (-1940 4710);
FORCEPROP 1 LASTPIN (-1950 4700) BN 4
J 0
(-1962 4708);
DISPLAY 0.680851 (-1962 4708);
PAINT GREEN (-1962 4708);
FORCEPROP 2 LAST CDS_LIB standard
J 0
(-1900 4700);
DISPLAY INVISIBLE (-1900 4700);
FORCEPROP 1 LAST BODY_TYPE PLUMBING
J 0
(-1900 4750);
DISPLAY 0.872340 (-1900 4750);
PAINT GREEN (-1900 4750);
DISPLAY INVISIBLE (-1900 4750);
FORCEPROP 1 LAST HDL_TAP TRUE
J 0
(-1575 4575);
DISPLAY 0.872340 (-1575 4575);
DISPLAY INVISIBLE (-1575 4575);
FORCEPROP 1 LAST PATH I28
J 0
(-1902 4700);
DISPLAY 0.872340 (-1902 4700);
PAINT GREEN (-1902 4700);
DISPLAY INVISIBLE (-1902 4700);
FORCEADD TAP..1
(-1900 5050);
FORCEPROP 3 LASTPIN (-1950 5050) SIG_NAME P5E_CPU1_P1_RX_DP<5>
J 0
(-1940 5060);
DISPLAY 0.659574 (-1940 5060);
PAINT MONO (-1940 5060);
DISPLAY INVISIBLE (-1940 5060);
FORCEPROP 1 LASTPIN (-1950 5050) BN 5
J 0
(-1962 5058);
DISPLAY 0.680851 (-1962 5058);
PAINT GREEN (-1962 5058);
FORCEPROP 2 LAST CDS_LIB standard
J 0
(-1900 5050);
DISPLAY INVISIBLE (-1900 5050);
FORCEPROP 1 LAST BODY_TYPE PLUMBING
J 0
(-1900 5100);
DISPLAY 0.872340 (-1900 5100);
PAINT GREEN (-1900 5100);
DISPLAY INVISIBLE (-1900 5100);
FORCEPROP 1 LAST HDL_TAP TRUE
J 0
(-1575 4925);
DISPLAY 0.872340 (-1575 4925);
DISPLAY INVISIBLE (-1575 4925);
FORCEPROP 1 LAST PATH I29
J 0
(-1902 5050);
DISPLAY 0.872340 (-1902 5050);
PAINT GREEN (-1902 5050);
DISPLAY INVISIBLE (-1902 5050);
FORCEADD TAP..1
(-6225 3125);
FORCEPROP 3 LASTPIN (-6275 3125) SIG_NAME P5E_CPU1_P1_RX_DN<8>
J 0
(-6265 3135);
DISPLAY 0.659574 (-6265 3135);
PAINT MONO (-6265 3135);
DISPLAY INVISIBLE (-6265 3135);
FORCEPROP 1 LASTPIN (-6275 3125) BN 8
J 0
(-6287 3133);
DISPLAY 0.680851 (-6287 3133);
PAINT GREEN (-6287 3133);
FORCEPROP 2 LAST CDS_LIB standard
J 0
(-6225 3125);
DISPLAY INVISIBLE (-6225 3125);
FORCEPROP 1 LAST BODY_TYPE PLUMBING
J 0
(-6225 3175);
DISPLAY 0.872340 (-6225 3175);
PAINT GREEN (-6225 3175);
DISPLAY INVISIBLE (-6225 3175);
FORCEPROP 1 LAST HDL_TAP TRUE
J 0
(-5900 3000);
DISPLAY 0.872340 (-5900 3000);
DISPLAY INVISIBLE (-5900 3000);
FORCEPROP 1 LAST PATH I3
J 0
(-6227 3125);
DISPLAY 0.872340 (-6227 3125);
PAINT GREEN (-6227 3125);
DISPLAY INVISIBLE (-6227 3125);
FORCEADD TAP..1
(-1900 5400);
FORCEPROP 3 LASTPIN (-1950 5400) SIG_NAME P5E_CPU1_P1_RX_DP<6>
J 0
(-1940 5410);
DISPLAY 0.659574 (-1940 5410);
PAINT MONO (-1940 5410);
DISPLAY INVISIBLE (-1940 5410);
FORCEPROP 1 LASTPIN (-1950 5400) BN 6
J 0
(-1962 5408);
DISPLAY 0.680851 (-1962 5408);
PAINT GREEN (-1962 5408);
FORCEPROP 2 LAST CDS_LIB standard
J 0
(-1900 5400);
DISPLAY INVISIBLE (-1900 5400);
FORCEPROP 1 LAST BODY_TYPE PLUMBING
J 0
(-1900 5450);
DISPLAY 0.872340 (-1900 5450);
PAINT GREEN (-1900 5450);
DISPLAY INVISIBLE (-1900 5450);
FORCEPROP 1 LAST HDL_TAP TRUE
J 0
(-1575 5275);
DISPLAY 0.872340 (-1575 5275);
DISPLAY INVISIBLE (-1575 5275);
FORCEPROP 1 LAST PATH I30
J 0
(-1902 5400);
DISPLAY 0.872340 (-1902 5400);
PAINT GREEN (-1902 5400);
DISPLAY INVISIBLE (-1902 5400);
FORCEADD TAP..1
(-1900 5750);
FORCEPROP 3 LASTPIN (-1950 5750) SIG_NAME P5E_CPU1_P1_RX_DP<7>
J 0
(-1940 5760);
DISPLAY 0.659574 (-1940 5760);
PAINT MONO (-1940 5760);
DISPLAY INVISIBLE (-1940 5760);
FORCEPROP 1 LASTPIN (-1950 5750) BN 7
J 0
(-1962 5758);
DISPLAY 0.680851 (-1962 5758);
PAINT GREEN (-1962 5758);
FORCEPROP 2 LAST CDS_LIB standard
J 0
(-1900 5750);
DISPLAY INVISIBLE (-1900 5750);
FORCEPROP 1 LAST BODY_TYPE PLUMBING
J 0
(-1900 5800);
DISPLAY 0.872340 (-1900 5800);
PAINT GREEN (-1900 5800);
DISPLAY INVISIBLE (-1900 5800);
FORCEPROP 1 LAST HDL_TAP TRUE
J 0
(-1575 5625);
DISPLAY 0.872340 (-1575 5625);
DISPLAY INVISIBLE (-1575 5625);
FORCEPROP 1 LAST PATH I31
J 0
(-1902 5750);
DISPLAY 0.872340 (-1902 5750);
PAINT GREEN (-1902 5750);
DISPLAY INVISIBLE (-1902 5750);
FORCEADD TAP..1
(-1700 4600);
FORCEPROP 3 LASTPIN (-1750 4600) SIG_NAME P5E_CPU1_P1_RX_DN<4>
J 0
(-1740 4610);
DISPLAY 0.659574 (-1740 4610);
PAINT MONO (-1740 4610);
DISPLAY INVISIBLE (-1740 4610);
FORCEPROP 1 LASTPIN (-1750 4600) BN 4
J 0
(-1762 4608);
DISPLAY 0.680851 (-1762 4608);
PAINT GREEN (-1762 4608);
FORCEPROP 2 LAST CDS_LIB standard
J 0
(-1700 4600);
DISPLAY INVISIBLE (-1700 4600);
FORCEPROP 1 LAST BODY_TYPE PLUMBING
J 0
(-1700 4650);
DISPLAY 0.872340 (-1700 4650);
PAINT GREEN (-1700 4650);
DISPLAY INVISIBLE (-1700 4650);
FORCEPROP 1 LAST HDL_TAP TRUE
J 0
(-1375 4475);
DISPLAY 0.872340 (-1375 4475);
DISPLAY INVISIBLE (-1375 4475);
FORCEPROP 1 LAST PATH I32
J 0
(-1702 4600);
DISPLAY 0.872340 (-1702 4600);
PAINT GREEN (-1702 4600);
DISPLAY INVISIBLE (-1702 4600);
FORCEADD TAP..1
(-1700 4950);
FORCEPROP 3 LASTPIN (-1750 4950) SIG_NAME P5E_CPU1_P1_RX_DN<5>
J 0
(-1740 4960);
DISPLAY 0.659574 (-1740 4960);
PAINT MONO (-1740 4960);
DISPLAY INVISIBLE (-1740 4960);
FORCEPROP 1 LASTPIN (-1750 4950) BN 5
J 0
(-1762 4958);
DISPLAY 0.680851 (-1762 4958);
PAINT GREEN (-1762 4958);
FORCEPROP 2 LAST CDS_LIB standard
J 0
(-1700 4950);
DISPLAY INVISIBLE (-1700 4950);
FORCEPROP 1 LAST BODY_TYPE PLUMBING
J 0
(-1700 5000);
DISPLAY 0.872340 (-1700 5000);
PAINT GREEN (-1700 5000);
DISPLAY INVISIBLE (-1700 5000);
FORCEPROP 1 LAST HDL_TAP TRUE
J 0
(-1375 4825);
DISPLAY 0.872340 (-1375 4825);
DISPLAY INVISIBLE (-1375 4825);
FORCEPROP 1 LAST PATH I33
J 0
(-1702 4950);
DISPLAY 0.872340 (-1702 4950);
PAINT GREEN (-1702 4950);
DISPLAY INVISIBLE (-1702 4950);
FORCEADD TAP..1
(-1700 5300);
FORCEPROP 3 LASTPIN (-1750 5300) SIG_NAME P5E_CPU1_P1_RX_DN<6>
J 0
(-1740 5310);
DISPLAY 0.659574 (-1740 5310);
PAINT MONO (-1740 5310);
DISPLAY INVISIBLE (-1740 5310);
FORCEPROP 1 LASTPIN (-1750 5300) BN 6
J 0
(-1762 5308);
DISPLAY 0.680851 (-1762 5308);
PAINT GREEN (-1762 5308);
FORCEPROP 2 LAST CDS_LIB standard
J 0
(-1700 5300);
DISPLAY INVISIBLE (-1700 5300);
FORCEPROP 1 LAST BODY_TYPE PLUMBING
J 0
(-1700 5350);
DISPLAY 0.872340 (-1700 5350);
PAINT GREEN (-1700 5350);
DISPLAY INVISIBLE (-1700 5350);
FORCEPROP 1 LAST HDL_TAP TRUE
J 0
(-1375 5175);
DISPLAY 0.872340 (-1375 5175);
DISPLAY INVISIBLE (-1375 5175);
FORCEPROP 1 LAST PATH I34
J 0
(-1702 5300);
DISPLAY 0.872340 (-1702 5300);
PAINT GREEN (-1702 5300);
DISPLAY INVISIBLE (-1702 5300);
FORCEADD TAP..1
(-1700 5650);
FORCEPROP 3 LASTPIN (-1750 5650) SIG_NAME P5E_CPU1_P1_RX_DN<7>
J 0
(-1740 5660);
DISPLAY 0.659574 (-1740 5660);
PAINT MONO (-1740 5660);
DISPLAY INVISIBLE (-1740 5660);
FORCEPROP 1 LASTPIN (-1750 5650) BN 7
J 0
(-1762 5658);
DISPLAY 0.680851 (-1762 5658);
PAINT GREEN (-1762 5658);
FORCEPROP 2 LAST CDS_LIB standard
J 0
(-1700 5650);
DISPLAY INVISIBLE (-1700 5650);
FORCEPROP 1 LAST BODY_TYPE PLUMBING
J 0
(-1700 5700);
DISPLAY 0.872340 (-1700 5700);
PAINT GREEN (-1700 5700);
DISPLAY INVISIBLE (-1700 5700);
FORCEPROP 1 LAST HDL_TAP TRUE
J 0
(-1375 5525);
DISPLAY 0.872340 (-1375 5525);
DISPLAY INVISIBLE (-1375 5525);
FORCEPROP 1 LAST PATH I35
J 0
(-1702 5650);
DISPLAY 0.872340 (-1702 5650);
PAINT GREEN (-1702 5650);
DISPLAY INVISIBLE (-1702 5650);
FORCEADD OFFPAGE..5
R 2
(-700 5675);
FORCEPROP 2 LAST $XR0 51 
J 0
(-511 5675);
DISPLAY 0.638298 (-511 5675);
PAINT MONO (-511 5675);
FORCEPROP 2 LAST CDS_LIB standard
J 0
(-700 5675);
DISPLAY INVISIBLE (-700 5675);
FORCEPROP 1 LAST OFFPAGE TRUE
J 2
(-1025 5550);
DISPLAY 0.872340 (-1025 5550);
PAINT GREEN (-1025 5550);
DISPLAY INVISIBLE (-1025 5550);
FORCEPROP 1 LAST COMMENT_BODY TRUE
J 2
(-800 5600);
DISPLAY 0.872340 (-800 5600);
PAINT GREEN (-800 5600);
DISPLAY INVISIBLE (-800 5600);
FORCEPROP 2 LAST PATH I36
J 0
(-525 5750);
DISPLAY 0.680851 (-525 5750);
DISPLAY INVISIBLE (-525 5750);
FORCEADD OFFPAGE..5
R 2
(-700 5775);
FORCEPROP 2 LAST $XR0 51 
J 0
(-511 5775);
DISPLAY 0.638298 (-511 5775);
PAINT MONO (-511 5775);
FORCEPROP 2 LAST CDS_LIB standard
J 0
(-700 5775);
DISPLAY INVISIBLE (-700 5775);
FORCEPROP 1 LAST OFFPAGE TRUE
J 2
(-1025 5650);
DISPLAY 0.872340 (-1025 5650);
PAINT GREEN (-1025 5650);
DISPLAY INVISIBLE (-1025 5650);
FORCEPROP 1 LAST COMMENT_BODY TRUE
J 2
(-800 5700);
DISPLAY 0.872340 (-800 5700);
PAINT GREEN (-800 5700);
DISPLAY INVISIBLE (-800 5700);
FORCEPROP 2 LAST PATH I37
J 0
(-525 5850);
DISPLAY 0.680851 (-525 5850);
DISPLAY INVISIBLE (-525 5850);
FORCEADD PT5161LRS..7
(-2925 4500);
FORCEPROP 1 LAST LOCATION U6015
J 0
(-3275 6125);
DISPLAY 0.723404 (-3275 6125);
PAINT GREEN (-3275 6125);
FORCEPROP 0 LAST $SEC 7
J 0
(-3275 6275);
DISPLAY 0.680851 (-3275 6275);
PAINT MONO (-3275 6275);
DISPLAY INVISIBLE (-3275 6275);
FORCEPROP 0 LAST CDS_SEC 7
J 0
(-3275 6275);
DISPLAY 0.680851 (-3275 6275);
DISPLAY INVISIBLE (-3275 6275);
FORCEPROP 0 LASTPIN (-2475 5650) $PN CK29
J 0
(-2465 5660);
DISPLAY 0.680851 (-2465 5660);
PAINT MONO (-2465 5660);
FORCEPROP 0 LASTPIN (-2475 5300) $PN CU29
J 0
(-2465 5310);
DISPLAY 0.680851 (-2465 5310);
PAINT MONO (-2465 5310);
FORCEPROP 0 LASTPIN (-2475 4950) $PN DD29
J 0
(-2465 4960);
DISPLAY 0.680851 (-2465 4960);
PAINT MONO (-2465 4960);
FORCEPROP 0 LASTPIN (-2475 4600) $PN DL29
J 0
(-2465 4610);
DISPLAY 0.680851 (-2465 4610);
PAINT MONO (-2465 4610);
FORCEPROP 0 LASTPIN (-2475 4250) $PN DV29
J 0
(-2465 4260);
DISPLAY 0.680851 (-2465 4260);
PAINT MONO (-2465 4260);
FORCEPROP 0 LASTPIN (-2475 3900) $PN EE29
J 0
(-2465 3910);
DISPLAY 0.680851 (-2465 3910);
PAINT MONO (-2465 3910);
FORCEPROP 0 LASTPIN (-2475 3550) $PN EM29
J 0
(-2465 3560);
DISPLAY 0.680851 (-2465 3560);
PAINT MONO (-2465 3560);
FORCEPROP 0 LASTPIN (-2475 3200) $PN EW29
J 0
(-2465 3210);
DISPLAY 0.680851 (-2465 3210);
PAINT MONO (-2465 3210);
FORCEPROP 0 LASTPIN (-2475 5750) $PN CH26
J 0
(-2465 5760);
DISPLAY 0.680851 (-2465 5760);
PAINT MONO (-2465 5760);
FORCEPROP 0 LASTPIN (-2475 5400) $PN CR26
J 0
(-2465 5410);
DISPLAY 0.680851 (-2465 5410);
PAINT MONO (-2465 5410);
FORCEPROP 0 LASTPIN (-2475 5050) $PN DB26
J 0
(-2465 5060);
DISPLAY 0.680851 (-2465 5060);
PAINT MONO (-2465 5060);
FORCEPROP 0 LASTPIN (-2475 4700) $PN DJ26
J 0
(-2465 4710);
DISPLAY 0.680851 (-2465 4710);
PAINT MONO (-2465 4710);
FORCEPROP 0 LASTPIN (-2475 4350) $PN DT26
J 0
(-2465 4360);
DISPLAY 0.680851 (-2465 4360);
PAINT MONO (-2465 4360);
FORCEPROP 0 LASTPIN (-2475 4000) $PN EC26
J 0
(-2465 4010);
DISPLAY 0.680851 (-2465 4010);
PAINT MONO (-2465 4010);
FORCEPROP 0 LASTPIN (-2475 3650) $PN EK26
J 0
(-2465 3660);
DISPLAY 0.680851 (-2465 3660);
PAINT MONO (-2465 3660);
FORCEPROP 0 LASTPIN (-2475 3300) $PN EU26
J 0
(-2465 3310);
DISPLAY 0.680851 (-2465 3310);
PAINT MONO (-2465 3310);
FORCEPROP 2 LAST VALUE PT5161LRS
J 0
(-3275 6175);
DISPLAY 0.680851 (-3275 6175);
FORCEPROP 1 LAST MATERIAL IC
J 0
(-3275 5975);
DISPLAY 0.723404 (-3275 5975);
PAINT GREEN (-3275 5975);
FORCEPROP 2 LAST PART_TYPE SMLF
J 0
(-3275 6225);
DISPLAY 0.680851 (-3275 6225);
FORCEPROP 1 LAST NEEDS_NO_SIZE TRUE
J 0
(-2925 4500);
DISPLAY 0.723404 (-2925 4500);
PAINT GREEN (-2925 4500);
DISPLAY INVISIBLE (-2925 4500);
FORCEPROP 1 LAST CDS_LMAN_SYM_OUTLINE -350,1450,300,-1400
J 0
(-2925 4500);
DISPLAY 0.468085 (-2925 4500);
PAINT GREEN (-2925 4500);
DISPLAY INVISIBLE (-2925 4500);
FORCEPROP 2 LAST CDS_LIB pure_quanta
J 0
(-2925 4500);
DISPLAY INVISIBLE (-2925 4500);
FORCEPROP 1 LAST PATH I38
J 0
(-2925 4500);
DISPLAY 0.723404 (-2925 4500);
PAINT GREEN (-2925 4500);
DISPLAY INVISIBLE (-2925 4500);
FORCEPROP 1 LAST PART_NUMBER AJ051610U03
J 0
(-3275 6050);
DISPLAY 0.723404 (-3275 6050);
PAINT GREEN (-3275 6050);
DISPLAY INVISIBLE (-3275 6050);
FORCEADD TAP..1
(-6425 4275);
FORCEPROP 3 LASTPIN (-6475 4275) SIG_NAME P5E_CPU1_P1_RX_DP<11>
J 0
(-6465 4285);
DISPLAY 0.659574 (-6465 4285);
PAINT MONO (-6465 4285);
DISPLAY INVISIBLE (-6465 4285);
FORCEPROP 1 LASTPIN (-6475 4275) BN 11
J 0
(-6487 4283);
DISPLAY 0.680851 (-6487 4283);
PAINT GREEN (-6487 4283);
FORCEPROP 2 LAST CDS_LIB standard
J 0
(-6425 4275);
DISPLAY INVISIBLE (-6425 4275);
FORCEPROP 1 LAST BODY_TYPE PLUMBING
J 0
(-6425 4325);
DISPLAY 0.872340 (-6425 4325);
PAINT GREEN (-6425 4325);
DISPLAY INVISIBLE (-6425 4325);
FORCEPROP 1 LAST HDL_TAP TRUE
J 0
(-6100 4150);
DISPLAY 0.872340 (-6100 4150);
DISPLAY INVISIBLE (-6100 4150);
FORCEPROP 1 LAST PATH I4
J 0
(-6427 4275);
DISPLAY 0.872340 (-6427 4275);
PAINT GREEN (-6427 4275);
DISPLAY INVISIBLE (-6427 4275);
FORCEADD TAP..1
(-6425 3925);
FORCEPROP 3 LASTPIN (-6475 3925) SIG_NAME P5E_CPU1_P1_RX_DP<10>
J 0
(-6465 3935);
DISPLAY 0.659574 (-6465 3935);
PAINT MONO (-6465 3935);
DISPLAY INVISIBLE (-6465 3935);
FORCEPROP 1 LASTPIN (-6475 3925) BN 10
J 0
(-6487 3933);
DISPLAY 0.680851 (-6487 3933);
PAINT GREEN (-6487 3933);
FORCEPROP 2 LAST CDS_LIB standard
J 0
(-6425 3925);
DISPLAY INVISIBLE (-6425 3925);
FORCEPROP 1 LAST BODY_TYPE PLUMBING
J 0
(-6425 3975);
DISPLAY 0.872340 (-6425 3975);
PAINT GREEN (-6425 3975);
DISPLAY INVISIBLE (-6425 3975);
FORCEPROP 1 LAST HDL_TAP TRUE
J 0
(-6100 3800);
DISPLAY 0.872340 (-6100 3800);
DISPLAY INVISIBLE (-6100 3800);
FORCEPROP 1 LAST PATH I5
J 0
(-6427 3925);
DISPLAY 0.872340 (-6427 3925);
PAINT GREEN (-6427 3925);
DISPLAY INVISIBLE (-6427 3925);
FORCEADD TAP..1
(-6425 3575);
FORCEPROP 3 LASTPIN (-6475 3575) SIG_NAME P5E_CPU1_P1_RX_DP<9>
J 0
(-6465 3585);
DISPLAY 0.659574 (-6465 3585);
PAINT MONO (-6465 3585);
DISPLAY INVISIBLE (-6465 3585);
FORCEPROP 1 LASTPIN (-6475 3575) BN 9
J 0
(-6487 3583);
DISPLAY 0.680851 (-6487 3583);
PAINT GREEN (-6487 3583);
FORCEPROP 2 LAST CDS_LIB standard
J 0
(-6425 3575);
DISPLAY INVISIBLE (-6425 3575);
FORCEPROP 1 LAST BODY_TYPE PLUMBING
J 0
(-6425 3625);
DISPLAY 0.872340 (-6425 3625);
PAINT GREEN (-6425 3625);
DISPLAY INVISIBLE (-6425 3625);
FORCEPROP 1 LAST HDL_TAP TRUE
J 0
(-6100 3450);
DISPLAY 0.872340 (-6100 3450);
DISPLAY INVISIBLE (-6100 3450);
FORCEPROP 1 LAST PATH I6
J 0
(-6427 3575);
DISPLAY 0.872340 (-6427 3575);
PAINT GREEN (-6427 3575);
DISPLAY INVISIBLE (-6427 3575);
FORCEADD TAP..1
(-6225 3475);
FORCEPROP 3 LASTPIN (-6275 3475) SIG_NAME P5E_CPU1_P1_RX_DN<9>
J 0
(-6265 3485);
DISPLAY 0.659574 (-6265 3485);
PAINT MONO (-6265 3485);
DISPLAY INVISIBLE (-6265 3485);
FORCEPROP 1 LASTPIN (-6275 3475) BN 9
J 0
(-6287 3483);
DISPLAY 0.680851 (-6287 3483);
PAINT GREEN (-6287 3483);
FORCEPROP 2 LAST CDS_LIB standard
J 0
(-6225 3475);
DISPLAY INVISIBLE (-6225 3475);
FORCEPROP 1 LAST BODY_TYPE PLUMBING
J 0
(-6225 3525);
DISPLAY 0.872340 (-6225 3525);
PAINT GREEN (-6225 3525);
DISPLAY INVISIBLE (-6225 3525);
FORCEPROP 1 LAST HDL_TAP TRUE
J 0
(-5900 3350);
DISPLAY 0.872340 (-5900 3350);
DISPLAY INVISIBLE (-5900 3350);
FORCEPROP 1 LAST PATH I7
J 0
(-6227 3475);
DISPLAY 0.872340 (-6227 3475);
PAINT GREEN (-6227 3475);
DISPLAY INVISIBLE (-6227 3475);
FORCEADD TAP..1
(-6225 3825);
FORCEPROP 3 LASTPIN (-6275 3825) SIG_NAME P5E_CPU1_P1_RX_DN<10>
J 0
(-6265 3835);
DISPLAY 0.659574 (-6265 3835);
PAINT MONO (-6265 3835);
DISPLAY INVISIBLE (-6265 3835);
FORCEPROP 1 LASTPIN (-6275 3825) BN 10
J 0
(-6287 3833);
DISPLAY 0.680851 (-6287 3833);
PAINT GREEN (-6287 3833);
FORCEPROP 2 LAST CDS_LIB standard
J 0
(-6225 3825);
DISPLAY INVISIBLE (-6225 3825);
FORCEPROP 1 LAST BODY_TYPE PLUMBING
J 0
(-6225 3875);
DISPLAY 0.872340 (-6225 3875);
PAINT GREEN (-6225 3875);
DISPLAY INVISIBLE (-6225 3875);
FORCEPROP 1 LAST HDL_TAP TRUE
J 0
(-5900 3700);
DISPLAY 0.872340 (-5900 3700);
DISPLAY INVISIBLE (-5900 3700);
FORCEPROP 1 LAST PATH I8
J 0
(-6227 3825);
DISPLAY 0.872340 (-6227 3825);
PAINT GREEN (-6227 3825);
DISPLAY INVISIBLE (-6227 3825);
FORCEADD TAP..1
(-6225 4175);
FORCEPROP 3 LASTPIN (-6275 4175) SIG_NAME P5E_CPU1_P1_RX_DN<11>
J 0
(-6265 4185);
DISPLAY 0.659574 (-6265 4185);
PAINT MONO (-6265 4185);
DISPLAY INVISIBLE (-6265 4185);
FORCEPROP 1 LASTPIN (-6275 4175) BN 11
J 0
(-6287 4183);
DISPLAY 0.680851 (-6287 4183);
PAINT GREEN (-6287 4183);
FORCEPROP 2 LAST CDS_LIB standard
J 0
(-6225 4175);
DISPLAY INVISIBLE (-6225 4175);
FORCEPROP 1 LAST BODY_TYPE PLUMBING
J 0
(-6225 4225);
DISPLAY 0.872340 (-6225 4225);
PAINT GREEN (-6225 4225);
DISPLAY INVISIBLE (-6225 4225);
FORCEPROP 1 LAST HDL_TAP TRUE
J 0
(-5900 4050);
DISPLAY 0.872340 (-5900 4050);
DISPLAY INVISIBLE (-5900 4050);
FORCEPROP 1 LAST PATH I9
J 0
(-6227 4175);
DISPLAY 0.872340 (-6227 4175);
PAINT GREEN (-6227 4175);
DISPLAY INVISIBLE (-6227 4175);
FORCEADD QUANTA_TITLE_BLOCK_C..1
(0 0);
FORCEPROP 0 LAST CDS_CON_LAST_MODIFIED Thu Sep 14 16:12:50 2023
J 0
(-1885 15);
DISPLAY INVISIBLE (-1885 15);
FORCEPROP 1 LAST CUSTOM_TXT_CDS <CON_LAST_MODIFIED>
J 0
(-1885 15);
DISPLAY 0.978723 (-1885 15);
FORCEPROP 2 LAST CUSTOM_TXT_CDS <XR_PAGE_TITLE>
J 0
(-7890 5250);
DISPLAY 0.638298 (-7890 5250);
PAINT PINK (-7890 5250);
DISPLAY INVISIBLE (-7890 5250);
FORCEPROP 1 LAST CUSTOM_TXT_CDS <NAME_2>
J 0
(-3175 50);
FORCEPROP 1 LAST CUSTOM_TXT_CDS <NAME_1>
J 0
(-3175 175);
FORCEPROP 1 LAST CUSTOM_TXT_CDS <Q_NUMBER>
J 0
(-1403 103);
DISPLAY 1.212766 (-1403 103);
FORCEPROP 1 LAST CUSTOM_TXT_CDS <Q_PROJ>
J 0
(-2382 102);
DISPLAY 1.212766 (-2382 102);
FORCEPROP 1 LAST CUSTOM_TXT_CDS <Q_REV>
J 0
(-184 103);
DISPLAY 1.212766 (-184 103);
FORCEPROP 1 LAST CUSTOM_TXT_CDS <CON_PAGE_NUM> OF <CON_TOTAL_PAGES>
J 0
(-446 18);
DISPLAY 0.978723 (-446 18);
FORCEPROP 1 LAST Q_TITLE RETIMER_CPU1_P1(2)
J 0
(-9366 26);
DISPLAY 2.446809 (-9366 26);
PAINT GREEN (-9366 26);
FORCEPROP 2 LAST PAGE_BORDER TRUE
J 0
(-7890 5250);
DISPLAY 0.638298 (-7890 5250);
PAINT PINK (-7890 5250);
DISPLAY INVISIBLE (-7890 5250);
FORCEPROP 1 LAST CDS_LMAN_SYM_OUTLINE -9475,6775,100,-125
J 0
(0 0);
DISPLAY 0.468085 (0 0);
PAINT GREEN (0 0);
DISPLAY INVISIBLE (0 0);
FORCEPROP 2 LAST CDS_LIB pure_quanta
J 0
(0 0);
DISPLAY INVISIBLE (0 0);
FORCEPROP 2 LAST CDS_XR_PAGE_TITLE CR-329 : @T6G_MB_LIB.T6G(SCH_1):PAGE329
J 0
(-7890 5250);
DISPLAY 0.638298 (-7890 5250);
PAINT PINK (-7890 5250);
DISPLAY INVISIBLE (-7890 5250);
FORCEPROP 1 LAST Q_DEPT BU9
J 1
(-3763 49);
DISPLAY 1.957447 (-3763 49);
PAINT GREEN (-3763 49);
DISPLAY INVISIBLE (-3763 49);
FORCEPROP 1 LAST COMMENT_BODY TRUE
J 0
(12 -13);
DISPLAY 0.978723 (12 -13);
PAINT GREEN (12 -13);
DISPLAY INVISIBLE (12 -13);
WIRE 17 -1 (-6375 5000)(-6375 4650);
WIRE 17 -1 (-6375 5350)(-6375 5000);
WIRE 17 -1 (-6375 4300)(-6375 4650);
WIRE 17 -1 (-6375 4300)(-6375 3950);
WIRE 17 -1 (-6375 5700)(-6375 5350);
WIRE 17 -1 (-6375 5775)(-6375 5700);
WIRE 17 -1 (-6375 3950)(-6375 3600);
WIRE 17 -1 (-6375 3600)(-6375 3250);
WIRE 17 -1 (-6375 5775)(-5250 5775);
FORCEPROP 2 LAST SIG_NAME P5E_CPU1_P1_RX_DP<15:8>
J 0
(-6110 5785);
DISPLAY 0.680851 (-6110 5785);
PAINT WHITE (-6110 5785);
WIRE 17 -1 (-1850 5775)(-750 5775);
FORCEPROP 2 LAST SIG_NAME P5E_CPU1_P1_RX_DP<7:0>
J 0
(-1585 5785);
DISPLAY 0.680851 (-1585 5785);
PAINT WHITE (-1585 5785);
WIRE 17 -1 (-1850 4375)(-1850 4025);
WIRE 17 -1 (-1850 4375)(-1850 4725);
WIRE 17 -1 (-1850 4025)(-1850 3675);
WIRE 17 -1 (-1850 3675)(-1850 3325);
WIRE 17 -1 (-1850 5075)(-1850 4725);
WIRE 17 -1 (-1850 5425)(-1850 5075);
WIRE 17 -1 (-1850 5775)(-1850 5425);
WIRE 17 -1 (-6175 4900)(-6175 4550);
WIRE 17 -1 (-6175 5250)(-6175 4900);
WIRE 17 -1 (-6175 4200)(-6175 4550);
WIRE 17 -1 (-6175 4200)(-6175 3850);
WIRE 17 -1 (-6175 5600)(-6175 5250);
WIRE 17 -1 (-6175 5650)(-6175 5600);
WIRE 17 -1 (-6175 3850)(-6175 3500);
WIRE 17 -1 (-6175 3500)(-6175 3150);
WIRE 17 -1 (-6175 5650)(-5275 5650);
FORCEPROP 2 LAST SIG_NAME P5E_CPU1_P1_RX_DN<15:8>
J 0
(-6110 5660);
DISPLAY 0.680851 (-6110 5660);
PAINT WHITE (-6110 5660);
WIRE 17 -1 (-1650 5675)(-1650 5325);
WIRE 17 -1 (-1650 5675)(-750 5675);
FORCEPROP 2 LAST SIG_NAME P5E_CPU1_P1_RX_DN<7:0>
J 0
(-1585 5685);
DISPLAY 0.680851 (-1585 5685);
PAINT WHITE (-1585 5685);
WIRE 17 -1 (-1650 3575)(-1650 3225);
WIRE 17 -1 (-1650 3925)(-1650 3575);
WIRE 17 -1 (-1650 4275)(-1650 3925);
WIRE 17 -1 (-1650 4275)(-1650 4625);
WIRE 17 -1 (-1650 4975)(-1650 4625);
WIRE 17 -1 (-1650 5325)(-1650 4975);
WIRE 16 -1 (-7000 5675)(-6475 5675);
WIRE 16 -1 (-7000 5225)(-6275 5225);
WIRE 16 -1 (-7000 5325)(-6475 5325);
WIRE 16 -1 (-7000 5575)(-6275 5575);
WIRE 16 -1 (-2475 3550)(-1750 3550);
WIRE 16 -1 (-2475 3900)(-1750 3900);
WIRE 16 -1 (-2475 4250)(-1750 4250);
WIRE 16 -1 (-2475 4600)(-1750 4600);
WIRE 16 -1 (-2475 4950)(-1750 4950);
WIRE 16 -1 (-2475 5650)(-1750 5650);
WIRE 16 -1 (-2475 3200)(-1750 3200);
WIRE 16 -1 (-2475 5300)(-1750 5300);
WIRE 16 -1 (-7000 4175)(-6275 4175);
WIRE 16 -1 (-7000 3825)(-6275 3825);
WIRE 16 -1 (-7000 3125)(-6275 3125);
WIRE 16 -1 (-7000 3475)(-6275 3475);
WIRE 16 -1 (-7000 4875)(-6275 4875);
WIRE 16 -1 (-7000 4525)(-6275 4525);
WIRE 16 -1 (-2475 4350)(-1950 4350);
WIRE 16 -1 (-2475 4700)(-1950 4700);
WIRE 16 -1 (-2475 5050)(-1950 5050);
WIRE 16 -1 (-2475 3300)(-1950 3300);
WIRE 16 -1 (-2475 3650)(-1950 3650);
WIRE 16 -1 (-2475 5400)(-1950 5400);
WIRE 16 -1 (-2475 4000)(-1950 4000);
WIRE 16 -1 (-2475 5750)(-1950 5750);
WIRE 16 -1 (-7000 3925)(-6475 3925);
WIRE 16 -1 (-7000 3575)(-6475 3575);
WIRE 16 -1 (-7000 3225)(-6475 3225);
WIRE 16 -1 (-7000 4275)(-6475 4275);
WIRE 16 -1 (-7000 4975)(-6475 4975);
WIRE 16 -1 (-6475 4625)(-7000 4625);
FORCENOTE
RETIMER TO CPU
(-3300 2750) 0;
DISPLAY LEFT (-3300 2750);
DISPLAY 3.148936 (-3300 2750);
FORCENOTE
RETIMER TO CPU
(-7800 2750) 0;
DISPLAY LEFT (-7800 2750);
DISPLAY 3.148936 (-7800 2750);
FORCENOTE
P5E_CPU1_P1_RX_DP/DN<0-15> LANE REVERSAL
(-9050 6325) 0;
DISPLAY LEFT (-9050 6325);
DISPLAY 2.000000 (-9050 6325);
QUIT
